# S9S_MB_2U (Grand Teton) — schematic netlist excerpt (pin names and nets, part order shuffled) for the footprints in the layout excerpt that follows; sources: Cadence DE-HDL packaged netlist, KiCad conversion of 03242023_DA0F0TMBIJ0_F0T_Motherboard_J_brd_V01_OCP.brd

R1271  Q_RES  2.21K 1% EMPTY  pkg 0402LF  page 194 : A = P3V3_AUX ; B = FM_PCH_SATA_RAID_KEY

PL8  Q_INDUCTOR4P_14  150NH IND  pkg L_TLM117513Q-151QL_11X7-5XA  page 270
  \1\  = SW_PVCCIN_CPU0_SW7
  \2\  = IND_P0_CPL7
  \3\  = IND_P0_CPL6
  \4\  = PVCCIN_CPU0

(kicad_pcb
	(version 20260206)
	(generator "pcbnew")
	(generator_version "10.0")
	(general
		(thickness 1.6)
		(legacy_teardrops no)
	)
	(paper "A4")
	(title_block
		(title "03242023_DA0F0TMBIJ0_F0T_Motherboard_J_brd_V01_OCP.brd")
		(comment 1 "Grand Teton / footprints 3377-3378 of 6105")
	)
	(layers
		(0 "F.Cu" signal "TOP")
		(4 "In1.Cu" signal "GND")
		(6 "In2.Cu" signal "IN1")
		(8 "In3.Cu" signal "GND1")
		(10 "In4.Cu" signal "IN2")
		(12 "In5.Cu" signal "GND2")
		(14 "In6.Cu" signal "IN3")
		(16 "In7.Cu" signal "GND3")
		(18 "In8.Cu" signal "VCC")
		(20 "In9.Cu" signal "VCC1")
		(22 "In10.Cu" signal "GND4")
		(24 "In11.Cu" signal "IN4")
		(26 "In12.Cu" signal "GND5")
		(28 "In13.Cu" signal "IN5")
		(30 "In14.Cu" signal "GND6")
		(32 "In15.Cu" signal "IN6")
		(34 "In16.Cu" signal "GND7")
		(2 "B.Cu" signal "BOTTOM")
		(9 "F.Adhes" user "F.Adhesive")
		(11 "B.Adhes" user "B.Adhesive")
		(13 "F.Paste" user "Package Geometry/Pastemask Top")
		(15 "B.Paste" user "Package Geometry/Pastemask Bottom")
		(5 "F.SilkS" user "Ref Des/Silkscreen Top")
		(7 "B.SilkS" user "Ref Des/Silkscreen Bottom")
		(1 "F.Mask" user "Board Geometry/Soldermask Top")
		(3 "B.Mask" user "Board Geometry/Soldermask Bottom")
		(17 "Dwgs.User" user "User.Drawings")
		(19 "Cmts.User" user "User.Comments")
		(21 "Eco1.User" user "User.Eco1")
		(23 "Eco2.User" user "User.Eco2")
		(25 "Edge.Cuts" user "Board Geometry/Outline")
		(27 "Margin" user)
		(31 "F.CrtYd" user "Package Geometry/Place Bound Top")
		(29 "B.CrtYd" user "Package Geometry/Place Bound Bottom")
		(35 "F.Fab" user "Ref Des/Assembly Top")
		(33 "B.Fab" user "Ref Des/Assembly Bottom")
	)
	(footprint ""
		(layer "F.Cu")
		(at 328.620882 -333.61884)
		(property "Reference" "PL8"
			(at -6.299962 4.735322 0)
			(unlocked yes)
			(layer "F.SilkS")
			(effects
				(font
					(size 0.7874 0.5842)
					(thickness 0.1524)
				)
				(justify left)
			)
		)
		(property "Value" ""
			(at 0 0 0)
			(layer "F.Fab")
			(effects
				(font
					(size 1.27 1.27)
				)
			)
		)
		(duplicate_pad_numbers_are_jumpers no)
		(fp_line
			(start -3.750056 -5.500116)
			(end -2.393442 -5.500116)
			(stroke
				(width 0.1524)
				(type default)
			)
			(layer "F.SilkS")
		)
		(fp_line
			(start -3.750056 5.500116)
			(end -3.750056 -5.500116)
			(stroke
				(width 0.1524)
				(type default)
			)
			(layer "F.SilkS")
		)
		(fp_line
			(start -2.393442 5.500116)
			(end -3.750056 5.500116)
			(stroke
				(width 0.1524)
				(type default)
			)
			(layer "F.SilkS")
		)
		(fp_line
			(start 2.393442 5.500116)
			(end 3.750056 5.500116)
			(stroke
				(width 0.1524)
				(type default)
			)
			(layer "F.SilkS")
		)
		(fp_line
			(start 3.750056 -5.500116)
			(end 2.393442 -5.500116)
			(stroke
				(width 0.1524)
				(type default)
			)
			(layer "F.SilkS")
		)
		(fp_line
			(start 3.750056 0.786892)
			(end 3.750056 -5.500116)
			(stroke
				(width 0.1524)
				(type default)
			)
			(layer "F.SilkS")
		)
		(fp_line
			(start 3.750056 5.500116)
			(end 3.750056 2.056892)
			(stroke
				(width 0.1524)
				(type default)
			)
			(layer "F.SilkS")
		)
		(fp_poly
			(pts
				(xy -3.060192 -6.962394) (xy -2.701036 -5.884672) (xy -3.778504 -6.244082)
			)
			(stroke
				(width 0)
				(type default)
			)
			(fill yes)
			(layer "F.SilkS")
		)
		(fp_line
			(start -3.750056 -5.500116)
			(end -3.750056 5.500116)
			(stroke
				(width 0.1)
				(type default)
			)
			(layer "F.Fab")
		)
		(fp_line
			(start -3.750056 5.500116)
			(end 3.750056 5.500116)
			(stroke
				(width 0.1)
				(type default)
			)
			(layer "F.Fab")
		)
		(fp_line
			(start 3.750056 -5.500116)
			(end -3.750056 -5.500116)
			(stroke
				(width 0.1)
				(type default)
			)
			(layer "F.Fab")
		)
		(fp_line
			(start 3.750056 5.500116)
			(end 3.750056 -5.500116)
			(stroke
				(width 0.1)
				(type default)
			)
			(layer "F.Fab")
		)
		(fp_poly
			(pts
				(xy -4.9276 -4.757928) (xy -4.9276 -3.741928) (xy -3.9116 -4.249928)
			)
			(stroke
				(width 0)
				(type default)
			)
			(fill yes)
			(layer "F.Fab")
		)
		(pad "1" smd rect
			(at 0 -4.249928 270)
			(size 2.413 4.5212)
			(layers "F.Cu" "F.Mask" "F.Paste")
			(net "SW_PVCCIN_CPU0_SW7")
		)
		(pad "2" smd rect
			(at 0 -1.175004 270)
			(size 1.3716 4.5212)
			(layers "F.Cu" "F.Mask" "F.Paste")
			(net "IND_P0_CPL7")
		)
		(pad "3" smd rect
			(at 0 1.175004 270)
			(size 1.3716 4.5212)
			(layers "F.Cu" "F.Mask" "F.Paste")
			(net "IND_P0_CPL6")
		)
		(pad "4" smd rect
			(at 0 4.249928 270)
			(size 2.413 4.5212)
			(layers "F.Cu" "F.Mask" "F.Paste")
			(net "PVCCIN_CPU0")
		)
	)
	(footprint ""
		(layer "F.Cu")
		(at 326.647302 -20.548346 90)
		(property "Reference" "R1271"
			(at 0 0 90)
			(layer "F.SilkS")
			(hide yes)
			(effects
				(font
					(size 1.27 1.27)
				)
			)
		)
		(property "Value" ""
			(at 0 0 90)
			(layer "F.Fab")
			(effects
				(font
					(size 1.27 1.27)
				)
			)
		)
		(duplicate_pad_numbers_are_jumpers no)
		(fp_line
			(start 0.7874 -0.4064)
			(end 0.7874 0.4064)
			(stroke
				(width 0.1524)
				(type default)
			)
			(layer "F.SilkS")
		)
		(fp_line
			(start -0.7874 -0.4064)
			(end 0.7874 -0.4064)
			(stroke
				(width 0.1524)
				(type default)
			)
			(layer "F.SilkS")
		)
		(fp_line
			(start 0.7874 0.4064)
			(end -0.7874 0.4064)
			(stroke
				(width 0.1524)
				(type default)
			)
			(layer "F.SilkS")
		)
		(fp_line
			(start -0.7874 0.4064)
			(end -0.7874 -0.4064)
			(stroke
				(width 0.1524)
				(type default)
			)
			(layer "F.SilkS")
		)
		(fp_line
			(start -0.12065 -0.305054)
			(end -0.12065 -0.2794)
			(stroke
				(width 0.1)
				(type default)
			)
			(layer "F.Fab")
		)
		(fp_line
			(start -0.67945 -0.305054)
			(end -0.12065 -0.305054)
			(stroke
				(width 0.1)
				(type default)
			)
			(layer "F.Fab")
		)
		(fp_line
			(start 0.67945 -0.3048)
			(end 0.67945 0.3048)
			(stroke
				(width 0.1)
				(type default)
			)
			(layer "F.Fab")
		)
		(fp_line
			(start 0.12065 -0.3048)
			(end 0.67945 -0.3048)
			(stroke
				(width 0.1)
				(type default)
			)
			(layer "F.Fab")
		)
		(fp_line
			(start 0.12065 -0.2794)
			(end 0.12065 -0.3048)
			(stroke
				(width 0.1)
				(type default)
			)
			(layer "F.Fab")
		)
		(fp_line
			(start -0.12065 -0.2794)
			(end 0.12065 -0.2794)
			(stroke
				(width 0.1)
				(type default)
			)
			(layer "F.Fab")
		)
		(fp_line
			(start 0.120396 0.2794)
			(end -0.12065 0.2794)
			(stroke
				(width 0.1)
				(type default)
			)
			(layer "F.Fab")
		)
		(fp_line
			(start -0.12065 0.2794)
			(end -0.12065 0.3048)
			(stroke
				(width 0.1)
				(type default)
			)
			(layer "F.Fab")
		)
		(fp_line
			(start 0.67945 0.3048)
			(end 0.120396 0.3048)
			(stroke
				(width 0.1)
				(type default)
			)
			(layer "F.Fab")
		)
		(fp_line
			(start 0.120396 0.3048)
			(end 0.120396 0.2794)
			(stroke
				(width 0.1)
				(type default)
			)
			(layer "F.Fab")
		)
		(fp_line
			(start -0.12065 0.3048)
			(end -0.67945 0.3048)
			(stroke
				(width 0.1)
				(type default)
			)
			(layer "F.Fab")
		)
		(fp_line
			(start -0.67945 0.3048)
			(end -0.67945 -0.305054)
			(stroke
				(width 0.1)
				(type default)
			)
			(layer "F.Fab")
		)
		(pad "1" smd circle
			(at -0.40005 0 90)
			(size 0 0)
			(layers "F.Cu" "F.Mask" "F.Paste")
			(net "P3V3_AUX")
		)
		(pad "2" smd circle
			(at 0.40005 0 90)
			(size 0 0)
			(layers "F.Cu" "F.Mask" "F.Paste")
			(net "FM_PCH_SATA_RAID_KEY")
		)
	)
)
